# S9S_MB_2U (Grand Teton) — schematic netlist excerpt (pin names and nets, part order shuffled) for the footprints in the layout excerpt that follows; sources: Cadence DE-HDL packaged netlist, KiCad conversion of 03242023_DA0F0TMBIJ0_F0T_Motherboard_J_brd_V01_OCP.brd

C1910  Q_CAP  0.01UF 50V 10% X7R  pkg C0402  page 217 : A = P3V3_AUX_FPGA_VCCIO0 ; B = GND
C470  Q_CAP  47UF 4V 20% X6S  pkg C0805  page 79 : A = PVCCFA_EHV_FIVRA_CPU1 ; B = GND
R1001  Q_RES  4.7K 5% CHIP  pkg 0402LF  page 235 : A = P3V3 ; B = FM_SMB_PEHPCPU1_PCIE_ALERT_R_N

(kicad_pcb
	(version 20260206)
	(generator "pcbnew")
	(generator_version "10.0")
	(general
		(thickness 1.6)
		(legacy_teardrops no)
	)
	(paper "A4")
	(title_block
		(title "03242023_DA0F0TMBIJ0_F0T_Motherboard_J_brd_V01_OCP.brd")
		(comment 1 "Grand Teton / footprints 4601-4603 of 6105")
	)
	(layers
		(0 "F.Cu" signal "TOP")
		(4 "In1.Cu" signal "GND")
		(6 "In2.Cu" signal "IN1")
		(8 "In3.Cu" signal "GND1")
		(10 "In4.Cu" signal "IN2")
		(12 "In5.Cu" signal "GND2")
		(14 "In6.Cu" signal "IN3")
		(16 "In7.Cu" signal "GND3")
		(18 "In8.Cu" signal "VCC")
		(20 "In9.Cu" signal "VCC1")
		(22 "In10.Cu" signal "GND4")
		(24 "In11.Cu" signal "IN4")
		(26 "In12.Cu" signal "GND5")
		(28 "In13.Cu" signal "IN5")
		(30 "In14.Cu" signal "GND6")
		(32 "In15.Cu" signal "IN6")
		(34 "In16.Cu" signal "GND7")
		(2 "B.Cu" signal "BOTTOM")
		(9 "F.Adhes" user "F.Adhesive")
		(11 "B.Adhes" user "B.Adhesive")
		(13 "F.Paste" user "Package Geometry/Pastemask Top")
		(15 "B.Paste" user "Package Geometry/Pastemask Bottom")
		(5 "F.SilkS" user "Ref Des/Silkscreen Top")
		(7 "B.SilkS" user "Ref Des/Silkscreen Bottom")
		(1 "F.Mask" user "Board Geometry/Soldermask Top")
		(3 "B.Mask" user "Board Geometry/Soldermask Bottom")
		(17 "Dwgs.User" user "User.Drawings")
		(19 "Cmts.User" user "User.Comments")
		(21 "Eco1.User" user "User.Eco1")
		(23 "Eco2.User" user "User.Eco2")
		(25 "Edge.Cuts" user "Board Geometry/Outline")
		(27 "Margin" user)
		(31 "F.CrtYd" user "Package Geometry/Place Bound Top")
		(29 "B.CrtYd" user "Package Geometry/Place Bound Bottom")
		(35 "F.Fab" user "Ref Des/Assembly Top")
		(33 "B.Fab" user "Ref Des/Assembly Bottom")
	)
	(footprint ""
		(layer "B.Cu")
		(at 170.555666 -116.975382)
		(property "Reference" "C1910"
			(at 0 0 0)
			(layer "B.SilkS")
			(hide yes)
			(effects
				(font
					(size 1.27 1.27)
				)
				(justify mirror)
			)
		)
		(property "Value" ""
			(at 0 0 0)
			(layer "B.Fab")
			(effects
				(font
					(size 1.27 1.27)
				)
				(justify mirror)
			)
		)
		(duplicate_pad_numbers_are_jumpers no)
		(fp_line
			(start -0.69215 -0.2921)
			(end -0.69215 0.2921)
			(stroke
				(width 0.1524)
				(type default)
			)
			(layer "B.SilkS")
		)
		(fp_line
			(start -0.69215 0.2921)
			(end 0.69215 0.2921)
			(stroke
				(width 0.1524)
				(type default)
			)
			(layer "B.SilkS")
		)
		(fp_line
			(start 0.69215 -0.2921)
			(end -0.69215 -0.2921)
			(stroke
				(width 0.1524)
				(type default)
			)
			(layer "B.SilkS")
		)
		(fp_line
			(start 0.69215 0.2921)
			(end 0.69215 -0.2921)
			(stroke
				(width 0.1524)
				(type default)
			)
			(layer "B.SilkS")
		)
		(fp_line
			(start -0.51435 -0.2794)
			(end -0.51435 0.2794)
			(stroke
				(width 0.1)
				(type default)
			)
			(layer "B.Fab")
		)
		(fp_line
			(start -0.51435 0.2794)
			(end 0.51435 0.2794)
			(stroke
				(width 0.1)
				(type default)
			)
			(layer "B.Fab")
		)
		(fp_line
			(start 0.51435 -0.2794)
			(end -0.51435 -0.2794)
			(stroke
				(width 0.1)
				(type default)
			)
			(layer "B.Fab")
		)
		(fp_line
			(start 0.51435 0.2794)
			(end 0.51435 -0.2794)
			(stroke
				(width 0.1)
				(type default)
			)
			(layer "B.Fab")
		)
		(pad "1" smd circle
			(at 0.40005 0 180)
			(size 0 0)
			(layers "B.Cu" "B.Mask" "B.Paste")
			(net "P3V3_AUX_FPGA_VCCIO0")
		)
		(pad "2" smd circle
			(at -0.40005 0 180)
			(size 0 0)
			(layers "B.Cu" "B.Mask" "B.Paste")
			(net "GND")
		)
		(zone
			(layer "B.Cu")
			(hatch none 0.5)
			(connect_pads
				(clearance 0)
			)
			(min_thickness 0.25)
			(keepout
				(tracks not_allowed)
				(vias allowed)
				(pads allowed)
				(copperpour not_allowed)
				(footprints allowed)
			)
			(placement
				(enabled no)
				(sheetname "")
			)
			(fill
				(thermal_gap 0.5)
				(thermal_bridge_width 0.5)
				(island_removal_mode 0)
			)
			(polygon
				(pts
					(xy 170.746166 -116.887752) (xy 170.654726 -116.829586) (xy 170.455336 -116.829586) (xy 170.365166 -116.887752)
					(xy 170.365166 -117.063012) (xy 170.455336 -117.121432) (xy 170.654726 -117.121432) (xy 170.746166 -117.063266)
				)
			)
		)
	)
	(footprint ""
		(layer "B.Cu")
		(at 88.401398 -184.01665 90)
		(property "Reference" "R1001"
			(at 0 0 90)
			(layer "B.SilkS")
			(hide yes)
			(effects
				(font
					(size 1.27 1.27)
				)
				(justify mirror)
			)
		)
		(property "Value" ""
			(at 0 0 90)
			(layer "B.Fab")
			(effects
				(font
					(size 1.27 1.27)
				)
				(justify mirror)
			)
		)
		(duplicate_pad_numbers_are_jumpers no)
		(fp_line
			(start 0.7874 -0.4064)
			(end -0.7874 -0.4064)
			(stroke
				(width 0.1524)
				(type default)
			)
			(layer "B.SilkS")
		)
		(fp_line
			(start -0.7874 -0.4064)
			(end -0.7874 0.4064)
			(stroke
				(width 0.1524)
				(type default)
			)
			(layer "B.SilkS")
		)
		(fp_line
			(start 0.7874 0.4064)
			(end 0.7874 -0.4064)
			(stroke
				(width 0.1524)
				(type default)
			)
			(layer "B.SilkS")
		)
		(fp_line
			(start -0.7874 0.4064)
			(end 0.7874 0.4064)
			(stroke
				(width 0.1524)
				(type default)
			)
			(layer "B.SilkS")
		)
		(fp_line
			(start 0.67945 -0.305054)
			(end 0.12065 -0.305054)
			(stroke
				(width 0.1)
				(type default)
			)
			(layer "B.Fab")
		)
		(fp_line
			(start 0.12065 -0.305054)
			(end 0.12065 -0.2794)
			(stroke
				(width 0.1)
				(type default)
			)
			(layer "B.Fab")
		)
		(fp_line
			(start -0.12065 -0.3048)
			(end -0.67945 -0.3048)
			(stroke
				(width 0.1)
				(type default)
			)
			(layer "B.Fab")
		)
		(fp_line
			(start -0.67945 -0.3048)
			(end -0.67945 0.3048)
			(stroke
				(width 0.1)
				(type default)
			)
			(layer "B.Fab")
		)
		(fp_line
			(start 0.12065 -0.2794)
			(end -0.12065 -0.2794)
			(stroke
				(width 0.1)
				(type default)
			)
			(layer "B.Fab")
		)
		(fp_line
			(start -0.12065 -0.2794)
			(end -0.12065 -0.3048)
			(stroke
				(width 0.1)
				(type default)
			)
			(layer "B.Fab")
		)
		(fp_line
			(start 0.12065 0.2794)
			(end 0.12065 0.3048)
			(stroke
				(width 0.1)
				(type default)
			)
			(layer "B.Fab")
		)
		(fp_line
			(start -0.120396 0.2794)
			(end 0.12065 0.2794)
			(stroke
				(width 0.1)
				(type default)
			)
			(layer "B.Fab")
		)
		(fp_line
			(start 0.67945 0.3048)
			(end 0.67945 -0.305054)
			(stroke
				(width 0.1)
				(type default)
			)
			(layer "B.Fab")
		)
		(fp_line
			(start 0.12065 0.3048)
			(end 0.67945 0.3048)
			(stroke
				(width 0.1)
				(type default)
			)
			(layer "B.Fab")
		)
		(fp_line
			(start -0.120396 0.3048)
			(end -0.120396 0.2794)
			(stroke
				(width 0.1)
				(type default)
			)
			(layer "B.Fab")
		)
		(fp_line
			(start -0.67945 0.3048)
			(end -0.120396 0.3048)
			(stroke
				(width 0.1)
				(type default)
			)
			(layer "B.Fab")
		)
		(pad "1" smd circle
			(at 0.40005 0 270)
			(size 0 0)
			(layers "B.Cu" "B.Mask" "B.Paste")
			(net "P3V3")
		)
		(pad "2" smd circle
			(at -0.40005 0 270)
			(size 0 0)
			(layers "B.Cu" "B.Mask" "B.Paste")
			(net "FM_SMB_PEHPCPU1_PCIE_ALERT_R_N")
		)
	)
	(footprint ""
		(layer "B.Cu")
		(at 64.904112 -258.472686 -90)
		(property "Reference" "C470"
			(at 0 0 90)
			(layer "B.SilkS")
			(hide yes)
			(effects
				(font
					(size 1.27 1.27)
				)
				(justify mirror)
			)
		)
		(property "Value" ""
			(at 0 0 90)
			(layer "B.Fab")
			(effects
				(font
					(size 1.27 1.27)
				)
				(justify mirror)
			)
		)
		(duplicate_pad_numbers_are_jumpers no)
		(fp_line
			(start -1.524 0.762)
			(end 1.524 0.762)
			(stroke
				(width 0.1524)
				(type default)
			)
			(layer "B.SilkS")
		)
		(fp_line
			(start 1.524 0.762)
			(end 1.524 -0.762)
			(stroke
				(width 0.1524)
				(type default)
			)
			(layer "B.SilkS")
		)
		(fp_line
			(start -1.524 -0.762)
			(end -1.524 0.762)
			(stroke
				(width 0.1524)
				(type default)
			)
			(layer "B.SilkS")
		)
		(fp_line
			(start 1.524 -0.762)
			(end -1.524 -0.762)
			(stroke
				(width 0.1524)
				(type default)
			)
			(layer "B.SilkS")
		)
		(fp_line
			(start -1.1049 0.724916)
			(end -1.1049 -0.724916)
			(stroke
				(width 0.1)
				(type default)
			)
			(layer "B.Fab")
		)
		(fp_line
			(start 1.1049 0.724916)
			(end -1.1049 0.724916)
			(stroke
				(width 0.1)
				(type default)
			)
			(layer "B.Fab")
		)
		(fp_line
			(start -1.1049 -0.724916)
			(end 1.1049 -0.724916)
			(stroke
				(width 0.1)
				(type default)
			)
			(layer "B.Fab")
		)
		(fp_line
			(start 1.1049 -0.724916)
			(end 1.1049 0.724916)
			(stroke
				(width 0.1)
				(type default)
			)
			(layer "B.Fab")
		)
		(pad "1" smd rect
			(at 0.889 0 270)
			(size 1.016 1.27)
			(layers "B.Cu" "B.Mask" "B.Paste")
			(net "PVCCFA_EHV_FIVRA_CPU1")
		)
		(pad "2" smd rect
			(at -0.889 0 270)
			(size 1.016 1.27)
			(layers "B.Cu" "B.Mask" "B.Paste")
			(net "GND")
		)
	)
)
